FILE_TYPE = CONNECTIVITY;
{Allegro Design Entry HDL 17.2-2016 S081 (4005846) 1/11/2022}
"PAGE_NUMBER" = 20;
0"NC";
1"M_A_CPU0_SA_CA<6:0>";
2"M_A_CPU0_SA_CS_N<3:0>";
3"M_A_CPU0_SA_DQS_DN<9:0>";
4"M_A_CPU0_SA_DQS_DP<9:0>";
5"M_A_CPU0_SB_CA<6:0>";
6"M_A_CPU0_SB_CS_N<3:0>";
7"M_A_CPU0_SB_DQS_DN<9:0>";
8"M_A_CPU0_SB_DQS_DP<9:0>";
9"M_A_CPU0_SB_CB<7:0>";
10"M_A_CPU0_SB_DQ<31:0>";
11"M_A_CPU0_SA_CB<7:0>";
12"M_A_CPU0_SA_DQ<31:0>";
13"M_A_CPU0_CLK_DP<1:0>";
14"M_A_CPU0_CLK_DN<1:0>";
15"M_A_CPU0_SA_DQ<16>";
16"M_A_CPU0_SA_DQ<15>";
17"M_A_CPU0_SA_DQ<14>";
18"M_A_CPU0_SA_DQ<13>";
19"M_A_CPU0_SA_DQ<12>";
20"M_A_CPU0_SA_DQ<11>";
21"M_A_CPU0_SA_DQ<10>";
22"M_A_CPU0_SA_DQ<8>";
23"M_A_CPU0_SA_DQ<7>";
24"M_A_CPU0_SA_DQ<5>";
25"M_A_CPU0_SA_DQ<2>";
26"M_A_CPU0_SA_DQ<0>";
27"M_A_CPU0_SA_CB<3>";
28"M_A_CPU0_SB_CA<6>";
29"M_A_CPU0_CLK_DN<1>";
30"M_A_CPU0_CLK_DN<0>";
31"M_A_CPU0_CLK_DP<1>";
32"M_A_CPU0_CLK_DP<0>";
33"M_A_CPU0_SA_DQ<31>";
34"M_A_CPU0_SA_DQ<30>";
35"M_A_CPU0_SA_DQ<29>";
36"M_A_CPU0_SA_DQ<28>";
37"M_A_CPU0_SA_DQ<27>";
38"M_A_CPU0_SA_DQ<26>";
39"M_A_CPU0_SA_DQ<25>";
40"M_A_CPU0_SA_DQ<24>";
41"M_A_CPU0_SA_DQ<23>";
42"M_A_CPU0_SA_DQ<22>";
43"M_A_CPU0_SA_DQ<21>";
44"M_A_CPU0_SA_DQ<20>";
45"M_A_CPU0_SA_DQ<19>";
46"M_A_CPU0_SA_DQ<18>";
47"M_A_CPU0_SA_DQ<17>";
48"M_A_CPU0_SA_DQ<9>";
49"M_A_CPU0_SA_DQ<6>";
50"M_A_CPU0_SA_DQ<4>";
51"M_A_CPU0_SA_DQ<3>";
52"M_A_CPU0_SA_DQ<1>";
53"M_A_CPU0_SA_CB<7>";
54"M_A_CPU0_SA_CB<6>";
55"M_A_CPU0_SA_CB<5>";
56"M_A_CPU0_SA_CB<4>";
57"M_A_CPU0_SA_CB<2>";
58"M_A_CPU0_SA_CB<1>";
59"M_A_CPU0_SA_CB<0>";
60"M_A_CPU0_SB_DQ<31>";
61"M_A_CPU0_SB_DQ<30>";
62"M_A_CPU0_SB_DQ<29>";
63"M_A_CPU0_SB_DQ<28>";
64"M_A_CPU0_SB_DQ<27>";
65"M_A_CPU0_SB_DQ<26>";
66"M_A_CPU0_SB_DQ<25>";
67"M_A_CPU0_SB_DQ<24>";
68"M_A_CPU0_SB_DQ<23>";
69"M_A_CPU0_SB_DQ<22>";
70"M_A_CPU0_SB_DQ<21>";
71"M_A_CPU0_SB_DQ<20>";
72"M_A_CPU0_SB_DQ<19>";
73"M_A_CPU0_SB_DQ<18>";
74"M_A_CPU0_SB_DQ<17>";
75"M_A_CPU0_SB_DQ<16>";
76"M_A_CPU0_SB_DQ<15>";
77"M_A_CPU0_SB_DQ<14>";
78"M_A_CPU0_SB_DQ<13>";
79"M_A_CPU0_SB_DQ<12>";
80"M_A_CPU0_SB_DQ<11>";
81"M_A_CPU0_SB_DQ<10>";
82"M_A_CPU0_SB_DQ<9>";
83"M_A_CPU0_SB_DQ<8>";
84"M_A_CPU0_SB_DQ<7>";
85"M_A_CPU0_SB_DQ<6>";
86"M_A_CPU0_SB_DQ<5>";
87"M_A_CPU0_SB_DQ<4>";
88"M_A_CPU0_SB_DQ<3>";
89"M_A_CPU0_SB_DQ<2>";
90"M_A_CPU0_SB_DQ<1>";
91"M_A_CPU0_SB_DQ<0>";
92"M_A_CPU0_SB_CB<7>";
93"M_A_CPU0_SB_CB<6>";
94"M_A_CPU0_SB_CB<5>";
95"M_A_CPU0_SB_CB<4>";
96"M_A_CPU0_SB_CB<3>";
97"M_A_CPU0_SB_CB<2>";
98"M_A_CPU0_SB_CB<1>";
99"M_A_CPU0_SB_CB<0>";
100"M_A_CPU0_SB_PAR";
101"M_A_CPU0_SB_DQS_DP<0>";
102"M_A_CPU0_SB_DQS_DP<1>";
103"M_A_CPU0_SB_DQS_DP<2>";
104"M_A_CPU0_SB_DQS_DP<3>";
105"M_A_CPU0_SB_DQS_DP<4>";
106"M_A_CPU0_SB_DQS_DP<5>";
107"M_A_CPU0_SB_DQS_DP<6>";
108"M_A_CPU0_SB_DQS_DP<7>";
109"M_A_CPU0_SB_DQS_DP<8>";
110"M_A_CPU0_SB_DQS_DP<9>";
111"M_A_CPU0_SB_DQS_DN<0>";
112"M_A_CPU0_SB_DQS_DN<1>";
113"M_A_CPU0_SB_DQS_DN<2>";
114"M_A_CPU0_SB_DQS_DN<3>";
115"M_A_CPU0_SB_DQS_DN<4>";
116"M_A_CPU0_SB_DQS_DN<5>";
117"M_A_CPU0_SB_DQS_DN<6>";
118"M_A_CPU0_SB_DQS_DN<7>";
119"M_A_CPU0_SB_DQS_DN<8>";
120"M_A_CPU0_SB_DQS_DN<9>";
121"M_A_CPU0_SB_CS_N<0>";
122"M_A_CPU0_SB_CS_N<1>";
123"M_A_CPU0_SB_CS_N<2>";
124"M_A_CPU0_SB_CS_N<3>";
125"M_A_CPU0_SB_CA<0>";
126"M_A_CPU0_SB_CA<1>";
127"M_A_CPU0_SB_CA<2>";
128"M_A_CPU0_SB_CA<3>";
129"M_A_CPU0_SB_CA<4>";
130"M_A_CPU0_SB_CA<5>";
131"M_A_CPU0_SA_PAR";
132"M_A_CPU0_SA_DQS_DP<0>";
133"M_A_CPU0_SA_DQS_DP<1>";
134"M_A_CPU0_SA_DQS_DP<2>";
135"M_A_CPU0_SA_DQS_DP<3>";
136"M_A_CPU0_SA_DQS_DP<4>";
137"M_A_CPU0_SA_DQS_DP<5>";
138"M_A_CPU0_SA_DQS_DP<6>";
139"M_A_CPU0_SA_DQS_DP<7>";
140"M_A_CPU0_SA_DQS_DP<8>";
141"M_A_CPU0_SA_DQS_DP<9>";
142"M_A_CPU0_SA_DQS_DN<0>";
143"M_A_CPU0_SA_DQS_DN<1>";
144"M_A_CPU0_SA_DQS_DN<2>";
145"M_A_CPU0_SA_DQS_DN<3>";
146"M_A_CPU0_SA_DQS_DN<4>";
147"M_A_CPU0_SA_DQS_DN<5>";
148"M_A_CPU0_SA_DQS_DN<6>";
149"M_A_CPU0_SA_DQS_DN<7>";
150"M_A_CPU0_SA_DQS_DN<8>";
151"M_A_CPU0_SA_DQS_DN<9>";
152"M_A_CPU0_SA_CS_N<0>";
153"M_A_CPU0_SA_CS_N<1>";
154"M_A_CPU0_SA_CS_N<2>";
155"M_A_CPU0_SA_CS_N<3>";
156"M_A_CPU0_SA_CA<0>";
157"M_A_CPU0_SA_CA<1>";
158"M_A_CPU0_SA_CA<2>";
159"M_A_CPU0_SA_CA<3>";
160"M_A_CPU0_SA_CA<4>";
161"M_A_CPU0_SA_CA<5>";
162"M_A_CPU0_SA_CA<6>";
163"M_A_CPU0_SB_RSP<0>";
164"M_A_CPU0_SB_RSP<1>";
165"M_A_CPU0_SA_RSP<0>";
166"M_A_CPU0_SA_RSP<1>";
167"M_A_CPU0_ALERT_N";
%"SOCKET4677_AZIF0045P001C01CS"
"8","(1100,2100)","0","pure_quanta","I1";
;
PART_NUMBER"DGA^7000023"
PART_TYPE"SMLF"
MATERIAL"IO"
VALUE"SOCKET4677_AZIF0045-P001C01CS"
$LOCATION"U2"
CDS_LIB"pure_quanta"
NEEDS_NO_SIZE"TRUE"
CDS_LMAN_SYM_OUTLINE"-1100,2250,1050,-2250"
CDS_LOCATION"U2"
$SEC"8"
CDS_SEC"8";
"DDR0_SB_PAR"
$PN"G39"100;
"DDR0_SB_ECC0"
$PN"B32"99;
"DDR0_SB_ECC1"
$PN"C31"98;
"DDR0_SB_ECC2"
$PN"F32"97;
"DDR0_SB_ECC3"
$PN"E31"96;
"DDR0_SB_ECC4"
$PN"C35"95;
"DDR0_SB_ECC5"
$PN"B34"94;
"DDR0_SB_ECC6"
$PN"E35"93;
"DDR0_SB_ECC7"
$PN"F34"92;
"DDR0_SB_DQS_DP0"
$PN"K30"101;
"DDR0_SB_DQS_DP1"
$PN"C27"102;
"DDR0_SB_DQS_DP2"
$PN"C21"103;
"DDR0_SB_DQS_DP3"
$PN"C9"104;
"DDR0_SB_DQS_DP4"
$PN"E33"105;
"DDR0_SB_DQS_DP5"
$PN"P30"106;
"DDR0_SB_DQS_DP6"
$PN"E27"107;
"DDR0_SB_DQS_DP7"
$PN"E21"108;
"DDR0_SB_DQS_DP8"
$PN"E9"109;
"DDR0_SB_DQS_DP9"
$PN"C33"110;
"DDR0_SB_DQS_DN0 \B"
$PN"H30"111;
"DDR0_SB_DQS_DN1 \B"
$PN"A27"112;
"DDR0_SB_DQS_DN2 \B"
$PN"A21"113;
"DDR0_SB_DQS_DN3 \B"
$PN"A9"114;
"DDR0_SB_DQS_DN4 \B"
$PN"G33"115;
"DDR0_SB_DQS_DN5 \B"
$PN"M30"116;
"DDR0_SB_DQS_DN6 \B"
$PN"G27"117;
"DDR0_SB_DQS_DN7 \B"
$PN"G21"118;
"DDR0_SB_DQS_DN8 \B"
$PN"G9"119;
"DDR0_SB_DQS_DN9 \B"
$PN"A33"120;
"DDR0_SB_DQ0"
$PN"K32"91;
"DDR0_SB_DQ1"
$PN"J31"90;
"DDR0_SB_DQ2"
$PN"M32"89;
"DDR0_SB_DQ3"
$PN"N31"88;
"DDR0_SB_DQ4"
$PN"J29"87;
"DDR0_SB_DQ5"
$PN"K28"86;
"DDR0_SB_DQ6"
$PN"N29"85;
"DDR0_SB_DQ7"
$PN"M28"84;
"DDR0_SB_DQ8"
$PN"C29"83;
"DDR0_SB_DQ9"
$PN"B28"82;
"DDR0_SB_DQ10"
$PN"E29"81;
"DDR0_SB_DQ11"
$PN"F28"80;
"DDR0_SB_DQ12"
$PN"B26"79;
"DDR0_SB_DQ13"
$PN"C25"78;
"DDR0_SB_DQ14"
$PN"F26"77;
"DDR0_SB_DQ15"
$PN"E25"76;
"DDR0_SB_DQ16"
$PN"C23"75;
"DDR0_SB_DQ17"
$PN"B22"74;
"DDR0_SB_DQ18"
$PN"E23"73;
"DDR0_SB_DQ19"
$PN"F22"72;
"DDR0_SB_DQ20"
$PN"B20"71;
"DDR0_SB_DQ21"
$PN"C19"70;
"DDR0_SB_DQ22"
$PN"F20"69;
"DDR0_SB_DQ23"
$PN"E19"68;
"DDR0_SB_DQ24"
$PN"C11"67;
"DDR0_SB_DQ25"
$PN"B10"66;
"DDR0_SB_DQ26"
$PN"E11"65;
"DDR0_SB_DQ27"
$PN"F10"64;
"DDR0_SB_DQ28"
$PN"B8"63;
"DDR0_SB_DQ29"
$PN"C7"62;
"DDR0_SB_DQ30"
$PN"F8"61;
"DDR0_SB_DQ31"
$PN"E7"60;
"DDR0_SB_CS_N0 \B"
$PN"B38"121;
"DDR0_SB_CS_N1 \B"
$PN"C37"122;
"DDR0_SB_CS_N2 \B"
$PN"F38"123;
"DDR0_SB_CS_N3 \B"
$PN"E37"124;
"DDR0_SB_CA0"
$PN"E43"125;
"DDR0_SB_CA1"
$PN"F44"126;
"DDR0_SB_CA2"
$PN"C41"127;
"DDR0_SB_CA3"
$PN"E41"128;
"DDR0_SB_CA4"
$PN"B40"129;
"DDR0_SB_CA5"
$PN"F40"130;
"DDR0_SB_CA6"
$PN"A39"28;
"DDR0_SA_PAR"
$PN"E48"131;
"DDR0_SA_ECC0"
$PN"C60"59;
"DDR0_SA_ECC1"
$PN"B59"58;
"DDR0_SA_ECC2"
$PN"E60"57;
"DDR0_SA_ECC3"
$PN"F59"27;
"DDR0_SA_ECC4"
$PN"B57"56;
"DDR0_SA_ECC5"
$PN"C56"55;
"DDR0_SA_ECC6"
$PN"F57"54;
"DDR0_SA_ECC7"
$PN"E56"53;
"DDR0_SA_DQS_DP0"
$PN"D77"132;
"DDR0_SA_DQS_DP1"
$PN"K67"133;
"DDR0_SA_DQS_DP2"
$PN"C70"134;
"DDR0_SA_DQS_DP3"
$PN"C64"135;
"DDR0_SA_DQS_DP4"
$PN"C58"136;
"DDR0_SA_DQS_DP5"
$PN"F77"137;
"DDR0_SA_DQS_DP6"
$PN"M67"138;
"DDR0_SA_DQS_DP7"
$PN"E70"139;
"DDR0_SA_DQS_DP8"
$PN"E64"140;
"DDR0_SA_DQS_DP9"
$PN"E58"141;
"DDR0_SA_DQS_DN0 \B"
$PN"B77"142;
"DDR0_SA_DQS_DN1 \B"
$PN"H67"143;
"DDR0_SA_DQS_DN2 \B"
$PN"B71"144;
"DDR0_SA_DQS_DN3 \B"
$PN"A64"145;
"DDR0_SA_DQS_DN4 \B"
$PN"A58"146;
"DDR0_SA_DQS_DN5 \B"
$PN"H77"147;
"DDR0_SA_DQS_DN6 \B"
$PN"P67"148;
"DDR0_SA_DQS_DN7 \B"
$PN"G70"149;
"DDR0_SA_DQS_DN8 \B"
$PN"G64"150;
"DDR0_SA_DQS_DN9 \B"
$PN"G58"151;
"DDR0_SA_DQ0"
$PN"B81"26;
"DDR0_SA_DQ1"
$PN"B79"52;
"DDR0_SA_DQ2"
$PN"M77"25;
"DDR0_SA_DQ3"
$PN"G78"51;
"DDR0_SA_DQ4"
$PN"C76"50;
"DDR0_SA_DQ5"
$PN"D75"24;
"DDR0_SA_DQ6"
$PN"G76"49;
"DDR0_SA_DQ7"
$PN"F75"23;
"DDR0_SA_DQ8"
$PN"K69"22;
"DDR0_SA_DQ9"
$PN"J68"48;
"DDR0_SA_DQ10"
$PN"M69"21;
"DDR0_SA_DQ11"
$PN"N68"20;
"DDR0_SA_DQ12"
$PN"J66"19;
"DDR0_SA_DQ13"
$PN"K65"18;
"DDR0_SA_DQ14"
$PN"N66"17;
"DDR0_SA_DQ15"
$PN"M65"16;
"DDR0_SA_DQ16"
$PN"B73"15;
"DDR0_SA_DQ17"
$PN"E72"47;
"DDR0_SA_DQ18"
$PN"D73"46;
"DDR0_SA_DQ19"
$PN"F71"45;
"DDR0_SA_DQ20"
$PN"B69"44;
"DDR0_SA_DQ21"
$PN"C68"43;
"DDR0_SA_DQ22"
$PN"F69"42;
"DDR0_SA_DQ23"
$PN"E68"41;
"DDR0_SA_DQ24"
$PN"C66"40;
"DDR0_SA_DQ25"
$PN"B65"39;
"DDR0_SA_DQ26"
$PN"E66"38;
"DDR0_SA_DQ27"
$PN"F65"37;
"DDR0_SA_DQ28"
$PN"B63"36;
"DDR0_SA_DQ29"
$PN"C62"35;
"DDR0_SA_DQ30"
$PN"F63"34;
"DDR0_SA_DQ31"
$PN"E62"33;
"DDR0_SA_CS_N0 \B"
$PN"C54"152;
"DDR0_SA_CS_N1 \B"
$PN"B53"153;
"DDR0_SA_CS_N2 \B"
$PN"E54"154;
"DDR0_SA_CS_N3 \B"
$PN"F53"155;
"DDR0_SA_CA0"
$PN"A52"156;
"DDR0_SA_CA1"
$PN"G52"157;
"DDR0_SA_CA2"
$PN"B51"158;
"DDR0_SA_CA3"
$PN"F51"159;
"DDR0_SA_CA4"
$PN"C50"160;
"DDR0_SA_CA5"
$PN"E50"161;
"DDR0_SA_CA6"
$PN"C48"162;
"DDR0_CLK_DP0"
$PN"C43"32;
"DDR0_CLK_DP1"
$PN"E45"31;
"DDR0_CLK_DN0 \B"
$PN"B44"30;
"DDR0_CLK_DN1 \B"
$PN"G45"29;
"DDR0_B_RSP0"
$PN"AV44"163;
"DDR0_B_RSP1"
$PN"AV42"164;
"DDR0_A_RSP0"
$PN"AT42"165;
"DDR0_A_RSP1"
$PN"AU43"166;
"DDR0_ALERT_N \B"
$PN"AT49"167;
%"TAP"
"1","(-625,3500)","2","standard","I10";
;
CDS_LIB"standard"
BODY_TYPE"PLUMBING"
HDL_TAP"TRUE";
"B \NAC \NWC"12;
"S \NAC"
BN"17"47;
%"TAP"
"1","(2800,3500)","0","standard","I100";
;
CDS_LIB"standard"
BODY_TYPE"PLUMBING"
HDL_TAP"TRUE";
"B \NAC \NWC"3;
"S \NAC"
BN"6"148;
%"TAP"
"1","(2800,3350)","0","standard","I101";
;
CDS_LIB"standard"
BODY_TYPE"PLUMBING"
HDL_TAP"TRUE";
"B \NAC \NWC"3;
"S \NAC"
BN"3"145;
%"TAP"
"1","(2800,3300)","0","standard","I102";
;
CDS_LIB"standard"
BODY_TYPE"PLUMBING"
HDL_TAP"TRUE";
"B \NAC \NWC"3;
"S \NAC"
BN"2"144;
%"TAP"
"1","(2800,3400)","0","standard","I103";
;
CDS_LIB"standard"
BODY_TYPE"PLUMBING"
HDL_TAP"TRUE";
"B \NAC \NWC"3;
"S \NAC"
BN"4"146;
%"TAP"
"1","(2800,3250)","0","standard","I104";
;
CDS_LIB"standard"
BODY_TYPE"PLUMBING"
HDL_TAP"TRUE";
"B \NAC \NWC"3;
"S \NAC"
BN"1"143;
%"TAP"
"1","(2800,3050)","0","standard","I106";
;
CDS_LIB"standard"
BODY_TYPE"PLUMBING"
HDL_TAP"TRUE";
"B \NAC \NWC"8;
"S \NAC"
BN"9"110;
%"TAP"
"1","(2800,3000)","0","standard","I107";
;
CDS_LIB"standard"
BODY_TYPE"PLUMBING"
HDL_TAP"TRUE";
"B \NAC \NWC"8;
"S \NAC"
BN"8"109;
%"TAP"
"1","(2800,2950)","0","standard","I108";
;
CDS_LIB"standard"
BODY_TYPE"PLUMBING"
HDL_TAP"TRUE";
"B \NAC \NWC"8;
"S \NAC"
BN"7"108;
%"TAP"
"1","(-625,3550)","2","standard","I11";
;
CDS_LIB"standard"
BODY_TYPE"PLUMBING"
HDL_TAP"TRUE";
"B \NAC \NWC"12;
"S \NAC"
BN"18"46;
%"TAP"
"1","(2800,2850)","0","standard","I110";
;
CDS_LIB"standard"
BODY_TYPE"PLUMBING"
HDL_TAP"TRUE";
"B \NAC \NWC"8;
"S \NAC"
BN"5"106;
%"TAP"
"1","(2800,2900)","0","standard","I111";
;
CDS_LIB"standard"
BODY_TYPE"PLUMBING"
HDL_TAP"TRUE";
"B \NAC \NWC"8;
"S \NAC"
BN"6"107;
%"TAP"
"1","(2800,2750)","0","standard","I112";
;
CDS_LIB"standard"
BODY_TYPE"PLUMBING"
HDL_TAP"TRUE";
"B \NAC \NWC"8;
"S \NAC"
BN"3"104;
%"TAP"
"1","(2800,2700)","0","standard","I113";
;
CDS_LIB"standard"
BODY_TYPE"PLUMBING"
HDL_TAP"TRUE";
"B \NAC \NWC"8;
"S \NAC"
BN"2"103;
%"TAP"
"1","(2800,2800)","0","standard","I114";
;
CDS_LIB"standard"
BODY_TYPE"PLUMBING"
HDL_TAP"TRUE";
"B \NAC \NWC"8;
"S \NAC"
BN"4"105;
%"TAP"
"1","(2800,2600)","0","standard","I115";
;
CDS_LIB"standard"
BODY_TYPE"PLUMBING"
HDL_TAP"TRUE";
"B \NAC \NWC"8;
"S \NAC"
BN"0"101;
%"TAP"
"1","(2800,2650)","0","standard","I116";
;
CDS_LIB"standard"
BODY_TYPE"PLUMBING"
HDL_TAP"TRUE";
"B \NAC \NWC"8;
"S \NAC"
BN"1"102;
%"TAP"
"1","(2800,2450)","0","standard","I117";
;
CDS_LIB"standard"
BODY_TYPE"PLUMBING"
HDL_TAP"TRUE";
"B \NAC \NWC"7;
"S \NAC"
BN"8"119;
%"TAP"
"1","(2800,2500)","0","standard","I118";
;
CDS_LIB"standard"
BODY_TYPE"PLUMBING"
HDL_TAP"TRUE";
"B \NAC \NWC"7;
"S \NAC"
BN"9"120;
%"TAP"
"1","(2800,2400)","0","standard","I119";
;
CDS_LIB"standard"
BODY_TYPE"PLUMBING"
HDL_TAP"TRUE";
"B \NAC \NWC"7;
"S \NAC"
BN"7"118;
%"TAP"
"1","(-625,3600)","2","standard","I12";
;
CDS_LIB"standard"
BODY_TYPE"PLUMBING"
HDL_TAP"TRUE";
"B \NAC \NWC"12;
"S \NAC"
BN"19"45;
%"TAP"
"1","(2800,2350)","0","standard","I120";
;
CDS_LIB"standard"
BODY_TYPE"PLUMBING"
HDL_TAP"TRUE";
"B \NAC \NWC"7;
"S \NAC"
BN"6"117;
%"TAP"
"1","(2800,2200)","0","standard","I121";
;
CDS_LIB"standard"
BODY_TYPE"PLUMBING"
HDL_TAP"TRUE";
"B \NAC \NWC"7;
"S \NAC"
BN"3"114;
%"TAP"
"1","(2800,2300)","0","standard","I122";
;
CDS_LIB"standard"
BODY_TYPE"PLUMBING"
HDL_TAP"TRUE";
"B \NAC \NWC"7;
"S \NAC"
BN"5"116;
%"TAP"
"1","(2800,2250)","0","standard","I123";
;
CDS_LIB"standard"
BODY_TYPE"PLUMBING"
HDL_TAP"TRUE";
"B \NAC \NWC"7;
"S \NAC"
BN"4"115;
%"TAP"
"1","(2800,2100)","0","standard","I124";
;
CDS_LIB"standard"
BODY_TYPE"PLUMBING"
HDL_TAP"TRUE";
"B \NAC \NWC"7;
"S \NAC"
BN"1"112;
%"TAP"
"1","(2800,2150)","0","standard","I125";
;
CDS_LIB"standard"
BODY_TYPE"PLUMBING"
HDL_TAP"TRUE";
"B \NAC \NWC"7;
"S \NAC"
BN"2"113;
%"TAP"
"1","(2800,2050)","0","standard","I126";
;
CDS_LIB"standard"
BODY_TYPE"PLUMBING"
HDL_TAP"TRUE";
"B \NAC \NWC"7;
"S \NAC"
BN"0"111;
%"TAP"
"1","(2800,1650)","0","standard","I127";
;
CDS_LIB"standard"
BODY_TYPE"PLUMBING"
HDL_TAP"TRUE";
"B \NAC \NWC"1;
"S \NAC"
BN"1"157;
%"TAP"
"1","(2800,1600)","0","standard","I128";
;
CDS_LIB"standard"
BODY_TYPE"PLUMBING"
HDL_TAP"TRUE";
"B \NAC \NWC"1;
"S \NAC"
BN"0"156;
%"TAP"
"1","(2800,1750)","0","standard","I129";
;
CDS_LIB"standard"
BODY_TYPE"PLUMBING"
HDL_TAP"TRUE";
"B \NAC \NWC"1;
"S \NAC"
BN"3"159;
%"TAP"
"1","(-625,3650)","2","standard","I13";
;
CDS_LIB"standard"
BODY_TYPE"PLUMBING"
HDL_TAP"TRUE";
"B \NAC \NWC"12;
"S \NAC"
BN"20"44;
%"TAP"
"1","(2800,1700)","0","standard","I130";
;
CDS_LIB"standard"
BODY_TYPE"PLUMBING"
HDL_TAP"TRUE";
"B \NAC \NWC"1;
"S \NAC"
BN"2"158;
%"TAP"
"1","(2800,1850)","0","standard","I131";
;
CDS_LIB"standard"
BODY_TYPE"PLUMBING"
HDL_TAP"TRUE";
"B \NAC \NWC"1;
"S \NAC"
BN"5"161;
%"TAP"
"1","(2800,1900)","0","standard","I132";
;
CDS_LIB"standard"
BODY_TYPE"PLUMBING"
HDL_TAP"TRUE";
"B \NAC \NWC"1;
"S \NAC"
BN"6"162;
%"TAP"
"1","(2800,1800)","0","standard","I133";
;
CDS_LIB"standard"
BODY_TYPE"PLUMBING"
HDL_TAP"TRUE";
"B \NAC \NWC"1;
"S \NAC"
BN"4"160;
%"TAP"
"1","(2800,1350)","0","standard","I138";
;
CDS_LIB"standard"
BODY_TYPE"PLUMBING"
HDL_TAP"TRUE";
"B \NAC \NWC"5;
"S \NAC"
BN"5"130;
%"TAP"
"1","(2800,1400)","0","standard","I139";
;
CDS_LIB"standard"
BODY_TYPE"PLUMBING"
HDL_TAP"TRUE";
"B \NAC \NWC"5;
"S \NAC"
BN"6"28;
%"TAP"
"1","(-625,3700)","2","standard","I14";
;
CDS_LIB"standard"
BODY_TYPE"PLUMBING"
HDL_TAP"TRUE";
"B \NAC \NWC"12;
"S \NAC"
BN"21"43;
%"TAP"
"1","(2800,1300)","0","standard","I140";
;
CDS_LIB"standard"
BODY_TYPE"PLUMBING"
HDL_TAP"TRUE";
"B \NAC \NWC"5;
"S \NAC"
BN"4"129;
%"TAP"
"1","(2800,1250)","0","standard","I141";
;
CDS_LIB"standard"
BODY_TYPE"PLUMBING"
HDL_TAP"TRUE";
"B \NAC \NWC"5;
"S \NAC"
BN"3"128;
%"TAP"
"1","(2800,1200)","0","standard","I142";
;
CDS_LIB"standard"
BODY_TYPE"PLUMBING"
HDL_TAP"TRUE";
"B \NAC \NWC"5;
"S \NAC"
BN"2"127;
%"TAP"
"1","(2800,1150)","0","standard","I143";
;
CDS_LIB"standard"
BODY_TYPE"PLUMBING"
HDL_TAP"TRUE";
"B \NAC \NWC"5;
"S \NAC"
BN"1"126;
%"TAP"
"1","(2800,1100)","0","standard","I144";
;
CDS_LIB"standard"
BODY_TYPE"PLUMBING"
HDL_TAP"TRUE";
"B \NAC \NWC"5;
"S \NAC"
BN"0"125;
%"TAP"
"1","(2800,800)","0","standard","I147";
;
CDS_LIB"standard"
BODY_TYPE"PLUMBING"
HDL_TAP"TRUE";
"B \NAC \NWC"2;
"S \NAC"
BN"1"153;
%"TAP"
"1","(2800,850)","0","standard","I148";
;
CDS_LIB"standard"
BODY_TYPE"PLUMBING"
HDL_TAP"TRUE";
"B \NAC \NWC"2;
"S \NAC"
BN"2"154;
%"TAP"
"1","(2800,900)","0","standard","I149";
;
CDS_LIB"standard"
BODY_TYPE"PLUMBING"
HDL_TAP"TRUE";
"B \NAC \NWC"2;
"S \NAC"
BN"3"155;
%"TAP"
"1","(-625,3750)","2","standard","I15";
;
CDS_LIB"standard"
BODY_TYPE"PLUMBING"
HDL_TAP"TRUE";
"B \NAC \NWC"12;
"S \NAC"
BN"22"42;
%"TAP"
"1","(2800,750)","0","standard","I150";
;
CDS_LIB"standard"
BODY_TYPE"PLUMBING"
HDL_TAP"TRUE";
"B \NAC \NWC"2;
"S \NAC"
BN"0"152;
%"TAP"
"1","(2800,600)","0","standard","I153";
;
CDS_LIB"standard"
BODY_TYPE"PLUMBING"
HDL_TAP"TRUE";
"B \NAC \NWC"6;
"S \NAC"
BN"3"124;
%"TAP"
"1","(2800,500)","0","standard","I154";
;
CDS_LIB"standard"
BODY_TYPE"PLUMBING"
HDL_TAP"TRUE";
"B \NAC \NWC"6;
"S \NAC"
BN"1"122;
%"TAP"
"1","(2800,550)","0","standard","I155";
;
CDS_LIB"standard"
BODY_TYPE"PLUMBING"
HDL_TAP"TRUE";
"B \NAC \NWC"6;
"S \NAC"
BN"2"123;
%"TAP"
"1","(2800,450)","0","standard","I156";
;
CDS_LIB"standard"
BODY_TYPE"PLUMBING"
HDL_TAP"TRUE";
"B \NAC \NWC"6;
"S \NAC"
BN"0"121;
%"TAP"
"1","(-625,3850)","2","standard","I16";
;
CDS_LIB"standard"
BODY_TYPE"PLUMBING"
HDL_TAP"TRUE";
"B \NAC \NWC"12;
"S \NAC"
BN"24"40;
%"TAP"
"1","(-625,500)","2","standard","I162";
;
CDS_LIB"standard"
BODY_TYPE"PLUMBING"
HDL_TAP"TRUE";
"B \NAC \NWC"9;
"S \NAC"
BN"5"94;
%"TAP"
"1","(-625,550)","2","standard","I163";
;
CDS_LIB"standard"
BODY_TYPE"PLUMBING"
HDL_TAP"TRUE";
"B \NAC \NWC"9;
"S \NAC"
BN"6"93;
%"TAP"
"1","(-625,600)","2","standard","I164";
;
CDS_LIB"standard"
BODY_TYPE"PLUMBING"
HDL_TAP"TRUE";
"B \NAC \NWC"9;
"S \NAC"
BN"7"92;
%"TAP"
"1","(-625,450)","2","standard","I165";
;
CDS_LIB"standard"
BODY_TYPE"PLUMBING"
HDL_TAP"TRUE";
"B \NAC \NWC"9;
"S \NAC"
BN"4"95;
%"TAP"
"1","(-625,400)","2","standard","I166";
;
CDS_LIB"standard"
BODY_TYPE"PLUMBING"
HDL_TAP"TRUE";
"B \NAC \NWC"9;
"S \NAC"
BN"3"96;
%"TAP"
"1","(-625,350)","2","standard","I167";
;
CDS_LIB"standard"
BODY_TYPE"PLUMBING"
HDL_TAP"TRUE";
"B \NAC \NWC"9;
"S \NAC"
BN"2"97;
%"TAP"
"1","(-625,300)","2","standard","I168";
;
CDS_LIB"standard"
BODY_TYPE"PLUMBING"
HDL_TAP"TRUE";
"B \NAC \NWC"9;
"S \NAC"
BN"1"98;
%"TAP"
"1","(-625,250)","2","standard","I169";
;
CDS_LIB"standard"
BODY_TYPE"PLUMBING"
HDL_TAP"TRUE";
"B \NAC \NWC"9;
"S \NAC"
BN"0"99;
%"TAP"
"1","(-625,3800)","2","standard","I17";
;
CDS_LIB"standard"
BODY_TYPE"PLUMBING"
HDL_TAP"TRUE";
"B \NAC \NWC"12;
"S \NAC"
BN"23"41;
%"TAP"
"1","(-625,150)","2","standard","I171";
;
CDS_LIB"standard"
BODY_TYPE"PLUMBING"
HDL_TAP"TRUE";
"B \NAC \NWC"13;
"S \NAC"
BN"1"31;
%"TAP"
"1","(-625,100)","2","standard","I172";
;
CDS_LIB"standard"
BODY_TYPE"PLUMBING"
HDL_TAP"TRUE";
"B \NAC \NWC"13;
"S \NAC"
BN"0"32;
%"TAP"
"1","(-625,50)","2","standard","I175";
;
CDS_LIB"standard"
BODY_TYPE"PLUMBING"
HDL_TAP"TRUE";
"B \NAC \NWC"14;
"S \NAC"
BN"1"29;
%"TAP"
"1","(-625,0)","2","standard","I176";
;
CDS_LIB"standard"
BODY_TYPE"PLUMBING"
HDL_TAP"TRUE";
"B \NAC \NWC"14;
"S \NAC"
BN"0"30;
%"TAP"
"1","(-625,3900)","2","standard","I18";
;
CDS_LIB"standard"
BODY_TYPE"PLUMBING"
HDL_TAP"TRUE";
"B \NAC \NWC"12;
"S \NAC"
BN"25"39;
%"TAP"
"1","(-625,3950)","2","standard","I19";
;
CDS_LIB"standard"
BODY_TYPE"PLUMBING"
HDL_TAP"TRUE";
"B \NAC \NWC"12;
"S \NAC"
BN"26"38;
%"TAP"
"1","(-625,4050)","2","standard","I20";
;
CDS_LIB"standard"
BODY_TYPE"PLUMBING"
HDL_TAP"TRUE";
"B \NAC \NWC"12;
"S \NAC"
BN"28"36;
%"TAP"
"1","(-625,4000)","2","standard","I21";
;
CDS_LIB"standard"
BODY_TYPE"PLUMBING"
HDL_TAP"TRUE";
"B \NAC \NWC"12;
"S \NAC"
BN"27"37;
%"TAP"
"1","(-625,4100)","2","standard","I22";
;
CDS_LIB"standard"
BODY_TYPE"PLUMBING"
HDL_TAP"TRUE";
"B \NAC \NWC"12;
"S \NAC"
BN"29"35;
%"TAP"
"1","(-625,4150)","2","standard","I23";
;
CDS_LIB"standard"
BODY_TYPE"PLUMBING"
HDL_TAP"TRUE";
"B \NAC \NWC"12;
"S \NAC"
BN"30"34;
%"TAP"
"1","(-625,4200)","2","standard","I24";
;
CDS_LIB"standard"
BODY_TYPE"PLUMBING"
HDL_TAP"TRUE";
"B \NAC \NWC"12;
"S \NAC"
BN"31"33;
%"TAP"
"1","(-625,2800)","2","standard","I25";
;
CDS_LIB"standard"
BODY_TYPE"PLUMBING"
HDL_TAP"TRUE";
"B \NAC \NWC"12;
"S \NAC"
BN"3"51;
%"TAP"
"1","(-625,2850)","2","standard","I26";
;
CDS_LIB"standard"
BODY_TYPE"PLUMBING"
HDL_TAP"TRUE";
"B \NAC \NWC"12;
"S \NAC"
BN"4"50;
%"TAP"
"1","(-625,2900)","2","standard","I27";
;
CDS_LIB"standard"
BODY_TYPE"PLUMBING"
HDL_TAP"TRUE";
"B \NAC \NWC"12;
"S \NAC"
BN"5"24;
%"TAP"
"1","(-625,2950)","2","standard","I28";
;
CDS_LIB"standard"
BODY_TYPE"PLUMBING"
HDL_TAP"TRUE";
"B \NAC \NWC"12;
"S \NAC"
BN"6"49;
%"TAP"
"1","(-625,3000)","2","standard","I29";
;
CDS_LIB"standard"
BODY_TYPE"PLUMBING"
HDL_TAP"TRUE";
"B \NAC \NWC"12;
"S \NAC"
BN"7"23;
%"TAP"
"1","(-625,2750)","2","standard","I3";
;
CDS_LIB"standard"
BODY_TYPE"PLUMBING"
HDL_TAP"TRUE";
"B \NAC \NWC"12;
"S \NAC"
BN"2"25;
%"TAP"
"1","(-625,3050)","2","standard","I30";
;
CDS_LIB"standard"
BODY_TYPE"PLUMBING"
HDL_TAP"TRUE";
"B \NAC \NWC"12;
"S \NAC"
BN"8"22;
%"TAP"
"1","(-625,3100)","2","standard","I31";
;
CDS_LIB"standard"
BODY_TYPE"PLUMBING"
HDL_TAP"TRUE";
"B \NAC \NWC"12;
"S \NAC"
BN"9"48;
%"TAP"
"1","(-625,3150)","2","standard","I32";
;
CDS_LIB"standard"
BODY_TYPE"PLUMBING"
HDL_TAP"TRUE";
"B \NAC \NWC"12;
"S \NAC"
BN"10"21;
%"TAP"
"1","(-625,2700)","2","standard","I33";
;
CDS_LIB"standard"
BODY_TYPE"PLUMBING"
HDL_TAP"TRUE";
"B \NAC \NWC"12;
"S \NAC"
BN"1"52;
%"TAP"
"1","(-625,2650)","2","standard","I34";
;
CDS_LIB"standard"
BODY_TYPE"PLUMBING"
HDL_TAP"TRUE";
"B \NAC \NWC"12;
"S \NAC"
BN"0"26;
%"TAP"
"1","(-625,2200)","2","standard","I35";
;
CDS_LIB"standard"
BODY_TYPE"PLUMBING"
HDL_TAP"TRUE";
"B \NAC \NWC"10;
"S \NAC"
BN"31"60;
%"TAP"
"1","(-625,2150)","2","standard","I36";
;
CDS_LIB"standard"
BODY_TYPE"PLUMBING"
HDL_TAP"TRUE";
"B \NAC \NWC"10;
"S \NAC"
BN"30"61;
%"TAP"
"1","(-625,2100)","2","standard","I37";
;
CDS_LIB"standard"
BODY_TYPE"PLUMBING"
HDL_TAP"TRUE";
"B \NAC \NWC"10;
"S \NAC"
BN"29"62;
%"TAP"
"1","(-625,1950)","2","standard","I39";
;
CDS_LIB"standard"
BODY_TYPE"PLUMBING"
HDL_TAP"TRUE";
"B \NAC \NWC"10;
"S \NAC"
BN"26"65;
%"TAP"
"1","(-625,3200)","2","standard","I4";
;
CDS_LIB"standard"
BODY_TYPE"PLUMBING"
HDL_TAP"TRUE";
"B \NAC \NWC"12;
"S \NAC"
BN"11"20;
%"TAP"
"1","(-625,2050)","2","standard","I40";
;
CDS_LIB"standard"
BODY_TYPE"PLUMBING"
HDL_TAP"TRUE";
"B \NAC \NWC"10;
"S \NAC"
BN"28"63;
%"TAP"
"1","(-625,2000)","2","standard","I41";
;
CDS_LIB"standard"
BODY_TYPE"PLUMBING"
HDL_TAP"TRUE";
"B \NAC \NWC"10;
"S \NAC"
BN"27"64;
%"TAP"
"1","(-625,1900)","2","standard","I42";
;
CDS_LIB"standard"
BODY_TYPE"PLUMBING"
HDL_TAP"TRUE";
"B \NAC \NWC"10;
"S \NAC"
BN"25"66;
%"TAP"
"1","(-625,1850)","2","standard","I43";
;
CDS_LIB"standard"
BODY_TYPE"PLUMBING"
HDL_TAP"TRUE";
"B \NAC \NWC"10;
"S \NAC"
BN"24"67;
%"TAP"
"1","(-625,1700)","2","standard","I44";
;
CDS_LIB"standard"
BODY_TYPE"PLUMBING"
HDL_TAP"TRUE";
"B \NAC \NWC"10;
"S \NAC"
BN"21"70;
%"TAP"
"1","(-625,1750)","2","standard","I45";
;
CDS_LIB"standard"
BODY_TYPE"PLUMBING"
HDL_TAP"TRUE";
"B \NAC \NWC"10;
"S \NAC"
BN"22"69;
%"TAP"
"1","(-625,1800)","2","standard","I46";
;
CDS_LIB"standard"
BODY_TYPE"PLUMBING"
HDL_TAP"TRUE";
"B \NAC \NWC"10;
"S \NAC"
BN"23"68;
%"TAP"
"1","(-625,1650)","2","standard","I47";
;
CDS_LIB"standard"
BODY_TYPE"PLUMBING"
HDL_TAP"TRUE";
"B \NAC \NWC"10;
"S \NAC"
BN"20"71;
%"TAP"
"1","(-625,1600)","2","standard","I48";
;
CDS_LIB"standard"
BODY_TYPE"PLUMBING"
HDL_TAP"TRUE";
"B \NAC \NWC"10;
"S \NAC"
BN"19"72;
%"TAP"
"1","(-625,1450)","2","standard","I49";
;
CDS_LIB"standard"
BODY_TYPE"PLUMBING"
HDL_TAP"TRUE";
"B \NAC \NWC"10;
"S \NAC"
BN"16"75;
%"TAP"
"1","(-625,3250)","2","standard","I5";
;
CDS_LIB"standard"
BODY_TYPE"PLUMBING"
HDL_TAP"TRUE";
"B \NAC \NWC"12;
"S \NAC"
BN"12"19;
%"TAP"
"1","(-625,1500)","2","standard","I50";
;
CDS_LIB"standard"
BODY_TYPE"PLUMBING"
HDL_TAP"TRUE";
"B \NAC \NWC"10;
"S \NAC"
BN"17"74;
%"TAP"
"1","(-625,1550)","2","standard","I51";
;
CDS_LIB"standard"
BODY_TYPE"PLUMBING"
HDL_TAP"TRUE";
"B \NAC \NWC"10;
"S \NAC"
BN"18"73;
%"TAP"
"1","(-625,1400)","2","standard","I52";
;
CDS_LIB"standard"
BODY_TYPE"PLUMBING"
HDL_TAP"TRUE";
"B \NAC \NWC"10;
"S \NAC"
BN"15"76;
%"TAP"
"1","(-625,1350)","2","standard","I53";
;
CDS_LIB"standard"
BODY_TYPE"PLUMBING"
HDL_TAP"TRUE";
"B \NAC \NWC"10;
"S \NAC"
BN"14"77;
%"TAP"
"1","(-625,1250)","2","standard","I54";
;
CDS_LIB"standard"
BODY_TYPE"PLUMBING"
HDL_TAP"TRUE";
"B \NAC \NWC"10;
"S \NAC"
BN"12"79;
%"TAP"
"1","(-625,1200)","2","standard","I55";
;
CDS_LIB"standard"
BODY_TYPE"PLUMBING"
HDL_TAP"TRUE";
"B \NAC \NWC"10;
"S \NAC"
BN"11"80;
%"TAP"
"1","(-625,1300)","2","standard","I56";
;
CDS_LIB"standard"
BODY_TYPE"PLUMBING"
HDL_TAP"TRUE";
"B \NAC \NWC"10;
"S \NAC"
BN"13"78;
%"TAP"
"1","(-625,1100)","2","standard","I57";
;
CDS_LIB"standard"
BODY_TYPE"PLUMBING"
HDL_TAP"TRUE";
"B \NAC \NWC"10;
"S \NAC"
BN"9"82;
%"TAP"
"1","(-625,1150)","2","standard","I58";
;
CDS_LIB"standard"
BODY_TYPE"PLUMBING"
HDL_TAP"TRUE";
"B \NAC \NWC"10;
"S \NAC"
BN"10"81;
%"TAP"
"1","(-625,1050)","2","standard","I59";
;
CDS_LIB"standard"
BODY_TYPE"PLUMBING"
HDL_TAP"TRUE";
"B \NAC \NWC"10;
"S \NAC"
BN"8"83;
%"TAP"
"1","(-625,3300)","2","standard","I6";
;
CDS_LIB"standard"
BODY_TYPE"PLUMBING"
HDL_TAP"TRUE";
"B \NAC \NWC"12;
"S \NAC"
BN"13"18;
%"TAP"
"1","(-625,950)","2","standard","I60";
;
CDS_LIB"standard"
BODY_TYPE"PLUMBING"
HDL_TAP"TRUE";
"B \NAC \NWC"10;
"S \NAC"
BN"6"85;
%"TAP"
"1","(-625,1000)","2","standard","I61";
;
CDS_LIB"standard"
BODY_TYPE"PLUMBING"
HDL_TAP"TRUE";
"B \NAC \NWC"10;
"S \NAC"
BN"7"84;
%"TAP"
"1","(-625,900)","2","standard","I62";
;
CDS_LIB"standard"
BODY_TYPE"PLUMBING"
HDL_TAP"TRUE";
"B \NAC \NWC"10;
"S \NAC"
BN"5"86;
%"TAP"
"1","(-625,850)","2","standard","I63";
;
CDS_LIB"standard"
BODY_TYPE"PLUMBING"
HDL_TAP"TRUE";
"B \NAC \NWC"10;
"S \NAC"
BN"4"87;
%"TAP"
"1","(-625,800)","2","standard","I64";
;
CDS_LIB"standard"
BODY_TYPE"PLUMBING"
HDL_TAP"TRUE";
"B \NAC \NWC"10;
"S \NAC"
BN"3"88;
%"TAP"
"1","(-625,650)","2","standard","I65";
;
CDS_LIB"standard"
BODY_TYPE"PLUMBING"
HDL_TAP"TRUE";
"B \NAC \NWC"10;
"S \NAC"
BN"0"91;
%"TAP"
"1","(-625,700)","2","standard","I66";
;
CDS_LIB"standard"
BODY_TYPE"PLUMBING"
HDL_TAP"TRUE";
"B \NAC \NWC"10;
"S \NAC"
BN"1"90;
%"TAP"
"1","(-625,750)","2","standard","I67";
;
CDS_LIB"standard"
BODY_TYPE"PLUMBING"
HDL_TAP"TRUE";
"B \NAC \NWC"10;
"S \NAC"
BN"2"89;
%"TAP"
"1","(-625,2350)","2","standard","I68";
;
CDS_LIB"standard"
BODY_TYPE"PLUMBING"
HDL_TAP"TRUE";
"B \NAC \NWC"11;
"S \NAC"
BN"2"57;
%"TAP"
"1","(-625,2250)","2","standard","I69";
;
CDS_LIB"standard"
BODY_TYPE"PLUMBING"
HDL_TAP"TRUE";
"B \NAC \NWC"11;
"S \NAC"
BN"0"59;
%"TAP"
"1","(-625,3350)","2","standard","I7";
;
CDS_LIB"standard"
BODY_TYPE"PLUMBING"
HDL_TAP"TRUE";
"B \NAC \NWC"12;
"S \NAC"
BN"14"17;
%"TAP"
"1","(-625,2450)","2","standard","I70";
;
CDS_LIB"standard"
BODY_TYPE"PLUMBING"
HDL_TAP"TRUE";
"B \NAC \NWC"11;
"S \NAC"
BN"4"56;
%"TAP"
"1","(-625,2600)","2","standard","I71";
;
CDS_LIB"standard"
BODY_TYPE"PLUMBING"
HDL_TAP"TRUE";
"B \NAC \NWC"11;
"S \NAC"
BN"7"53;
%"TAP"
"1","(-625,2550)","2","standard","I72";
;
CDS_LIB"standard"
BODY_TYPE"PLUMBING"
HDL_TAP"TRUE";
"B \NAC \NWC"11;
"S \NAC"
BN"6"54;
%"TAP"
"1","(-625,2500)","2","standard","I73";
;
CDS_LIB"standard"
BODY_TYPE"PLUMBING"
HDL_TAP"TRUE";
"B \NAC \NWC"11;
"S \NAC"
BN"5"55;
%"TAP"
"1","(-625,2400)","2","standard","I75";
;
CDS_LIB"standard"
BODY_TYPE"PLUMBING"
HDL_TAP"TRUE";
"B \NAC \NWC"11;
"S \NAC"
BN"3"27;
%"TAP"
"1","(-625,2300)","2","standard","I76";
;
CDS_LIB"standard"
BODY_TYPE"PLUMBING"
HDL_TAP"TRUE";
"B \NAC \NWC"11;
"S \NAC"
BN"1"58;
%"TAP"
"1","(-625,3400)","2","standard","I8";
;
CDS_LIB"standard"
BODY_TYPE"PLUMBING"
HDL_TAP"TRUE";
"B \NAC \NWC"12;
"S \NAC"
BN"15"16;
%"TAP"
"1","(2800,3750)","0","standard","I82";
;
CDS_LIB"standard"
BODY_TYPE"PLUMBING"
HDL_TAP"TRUE";
"B \NAC \NWC"4;
"S \NAC"
BN"0"132;
%"TAP"
"1","(2800,3850)","0","standard","I84";
;
CDS_LIB"standard"
BODY_TYPE"PLUMBING"
HDL_TAP"TRUE";
"B \NAC \NWC"4;
"S \NAC"
BN"2"134;
%"TAP"
"1","(2800,3800)","0","standard","I85";
;
CDS_LIB"standard"
BODY_TYPE"PLUMBING"
HDL_TAP"TRUE";
"B \NAC \NWC"4;
"S \NAC"
BN"1"133;
%"TAP"
"1","(2800,3900)","0","standard","I86";
;
CDS_LIB"standard"
BODY_TYPE"PLUMBING"
HDL_TAP"TRUE";
"B \NAC \NWC"4;
"S \NAC"
BN"3"135;
%"TAP"
"1","(2800,3950)","0","standard","I87";
;
CDS_LIB"standard"
BODY_TYPE"PLUMBING"
HDL_TAP"TRUE";
"B \NAC \NWC"4;
"S \NAC"
BN"4"136;
%"TAP"
"1","(2800,4050)","0","standard","I88";
;
CDS_LIB"standard"
BODY_TYPE"PLUMBING"
HDL_TAP"TRUE";
"B \NAC \NWC"4;
"S \NAC"
BN"6"138;
%"TAP"
"1","(2800,4000)","0","standard","I89";
;
CDS_LIB"standard"
BODY_TYPE"PLUMBING"
HDL_TAP"TRUE";
"B \NAC \NWC"4;
"S \NAC"
BN"5"137;
%"TAP"
"1","(-625,3450)","2","standard","I9";
;
CDS_LIB"standard"
BODY_TYPE"PLUMBING"
HDL_TAP"TRUE";
"B \NAC \NWC"12;
"S \NAC"
BN"16"15;
%"TAP"
"1","(2800,4100)","0","standard","I90";
;
CDS_LIB"standard"
BODY_TYPE"PLUMBING"
HDL_TAP"TRUE";
"B \NAC \NWC"4;
"S \NAC"
BN"7"139;
%"TAP"
"1","(2800,4150)","0","standard","I91";
;
CDS_LIB"standard"
BODY_TYPE"PLUMBING"
HDL_TAP"TRUE";
"B \NAC \NWC"4;
"S \NAC"
BN"8"140;
%"TAP"
"1","(2800,4200)","0","standard","I92";
;
CDS_LIB"standard"
BODY_TYPE"PLUMBING"
HDL_TAP"TRUE";
"B \NAC \NWC"4;
"S \NAC"
BN"9"141;
%"TAP"
"1","(2800,3200)","0","standard","I94";
;
CDS_LIB"standard"
BODY_TYPE"PLUMBING"
HDL_TAP"TRUE";
"B \NAC \NWC"3;
"S \NAC"
BN"0"142;
%"TAP"
"1","(2800,3650)","0","standard","I96";
;
CDS_LIB"standard"
BODY_TYPE"PLUMBING"
HDL_TAP"TRUE";
"B \NAC \NWC"3;
"S \NAC"
BN"9"151;
%"TAP"
"1","(2800,3600)","0","standard","I97";
;
CDS_LIB"standard"
BODY_TYPE"PLUMBING"
HDL_TAP"TRUE";
"B \NAC \NWC"3;
"S \NAC"
BN"8"150;
%"TAP"
"1","(2800,3550)","0","standard","I98";
;
CDS_LIB"standard"
BODY_TYPE"PLUMBING"
HDL_TAP"TRUE";
"B \NAC \NWC"3;
"S \NAC"
BN"7"149;
%"TAP"
"1","(2800,3450)","0","standard","I99";
;
CDS_LIB"standard"
BODY_TYPE"PLUMBING"
HDL_TAP"TRUE";
"B \NAC \NWC"3;
"S \NAC"
BN"5"147;
END.
